# BASEBOARD_FAB2 (Tioga Pass) — schematic netlist excerpt (pin names and nets, part order shuffled) for the footprints in the layout excerpt that follows; sources: Cadence DE-HDL packaged netlist, KiCad conversion of Wiwynn_Tioga_Pass_MB.brd

EU4A3  NCP3232L  IC  pkg SM  page 234
  SS  = VR_PVPP_KLM_SS
  FB  = VR_FB_PVPP_KLM
  COMP  = VR_COMP_PVPP_KLM_3
  ISET  = VR_PVPP_KLM_ISET
  AGND  = AGND_PVPP_KLM
  OTS  = AGND_PVPP_KLM
  PG  = PWRGD_PVPP_KLM_R
  VIN(0)  = VR_FET_SW_P12V_STBY_PVPP_KLM
  VIN(1)  = VR_FET_SW_P12V_STBY_PVPP_KLM
  VIN(2)  = VR_FET_SW_P12V_STBY_PVPP_KLM
  VIN(3)  = VR_FET_SW_P12V_STBY_PVPP_KLM
  VIN(4)  = VR_FET_SW_P12V_STBY_PVPP_KLM
  VIN(5)  = VR_FET_SW_P12V_STBY_PVPP_KLM
  VIN(6)  = VR_FET_SW_P12V_STBY_PVPP_KLM
  VSWH(0)  = VR_PVPP_KLM_PHASE
  PGND(0)  = GND
  PGND(1)  = GND
  PGND(2)  = GND
  PGND(3)  = GND
  PGND(4)  = GND
  PGND(5)  = GND
  PGND(6)  = GND
  PGND(7)  = GND
  PGND(8)  = GND
  PGND(9)  = GND
  PGND(10)  = GND
  PGND(11)  = GND
  PGND(12)  = GND
  VSWH(1)  = VR_PVPP_KLM_PHASE
  VSWH(2)  = VR_PVPP_KLM_PHASE
  VSWH(3)  = VR_PVPP_KLM_PHASE
  VSWH(4)  = VR_PVPP_KLM_PHASE
  VSWH(5)  = VR_PVPP_KLM_PHASE
  VSWH(6)  = VR_PVPP_KLM_PHASE
  VSW  = VR_PVPP_KLM_PHASE
  BST  = VR_PVPP_KLM_BOOT
  PGND(13)  = GND
  VB  = VR_VB_PVPP_KLM
  VCC  = VR_FET_SW_P12V_STBY_PVPP_KLM
  EN  = FM_PVPP_PVDDQ_CPU1_EN_KLM
  GND  = GND
  VIN(7)  = VR_FET_SW_P12V_STBY_PVPP_KLM
  VSWH(7)  = VR_PVPP_KLM_PHASE

(kicad_pcb
	(version 20260206)
	(generator "pcbnew")
	(generator_version "10.0")
	(general
		(thickness 1.6)
		(legacy_teardrops no)
	)
	(paper "A4")
	(title_block
		(title "Wiwynn_Tioga_Pass_MB.brd")
		(comment 1 "Tioga Pass / footprint 2008 of 4770 (EU4A3), pads 1-17 of 43")
	)
	(layers
		(0 "F.Cu" signal "TOP")
		(4 "In1.Cu" signal "L2GND")
		(6 "In2.Cu" signal "L3")
		(8 "In3.Cu" signal "L4GND")
		(10 "In4.Cu" signal "L5")
		(12 "In5.Cu" signal "L6GND")
		(14 "In6.Cu" signal "L7VCC")
		(16 "In7.Cu" signal "L8VCC")
		(18 "In8.Cu" signal "L9GND")
		(20 "In9.Cu" signal "L10")
		(22 "In10.Cu" signal "L11GND")
		(24 "In11.Cu" signal "L12")
		(26 "In12.Cu" signal "L13GND")
		(2 "B.Cu" signal "BOTTOM")
		(9 "F.Adhes" user "F.Adhesive")
		(11 "B.Adhes" user "B.Adhesive")
		(13 "F.Paste" user "Package Geometry/Pastemask Top")
		(15 "B.Paste" user "Package Geometry/Pastemask Bottom")
		(5 "F.SilkS" user "Ref Des/Silkscreen Top")
		(7 "B.SilkS" user "Ref Des/Silkscreen Bottom")
		(1 "F.Mask" user "Board Geometry/Soldermask Top")
		(3 "B.Mask" user "Board Geometry/Soldermask Bottom")
		(17 "Dwgs.User" user "User.Drawings")
		(19 "Cmts.User" user "User.Comments")
		(21 "Eco1.User" user "User.Eco1")
		(23 "Eco2.User" user "User.Eco2")
		(25 "Edge.Cuts" user "Board Geometry/Outline")
		(27 "Margin" user)
		(31 "F.CrtYd" user "Package Geometry/Place Bound Top")
		(29 "B.CrtYd" user "Package Geometry/Place Bound Bottom")
		(35 "F.Fab" user "Ref Des/Assembly Top")
		(33 "B.Fab" user "Ref Des/Assembly Bottom")
	)
	(footprint ""
		(layer "F.Cu")
		(at 177.673 -136.8425 90)
		(property "Reference" "EU4A3"
			(at 5.29463 0.1778 0)
			(unlocked yes)
			(layer "F.SilkS")
			(effects
				(font
					(size 0.7874 0.5842)
					(thickness 0.1524)
				)
				(justify left)
			)
		)
		(property "Value" ""
			(at 0 0 90)
			(layer "F.Fab")
			(effects
				(font
					(size 1.27 1.27)
				)
			)
		)
		(duplicate_pad_numbers_are_jumpers no)
		(pad "1" smd custom
			(at -2.8321 -2.249932 90)
			(size 0.06985 0.06985)
			(layers "F.Cu" "F.Mask" "F.Paste")
			(net "VR_PVPP_KLM_SS")
			(options
				(clearance outline)
				(anchor circle)
			)
			(primitives
				(gr_poly
					(pts
						(arc
							(start 0.2413 -0.1397)
							(mid 0.381 0)
							(end 0.2413 0.1397)
						)
						(xy -0.381 0.1397) (xy -0.381 -0.1397)
					)
					(width 0)
					(fill yes)
				)
			)
		)
		(pad "2" smd custom
			(at -2.8321 -1.75006 90)
			(size 0.06985 0.06985)
			(layers "F.Cu" "F.Mask" "F.Paste")
			(net "VR_FB_PVPP_KLM")
			(options
				(clearance outline)
				(anchor circle)
			)
			(primitives
				(gr_poly
					(pts
						(arc
							(start 0.2413 -0.1397)
							(mid 0.381 0)
							(end 0.2413 0.1397)
						)
						(xy -0.381 0.1397) (xy -0.381 -0.1397)
					)
					(width 0)
					(fill yes)
				)
			)
		)
		(pad "3" smd custom
			(at -2.8321 -1.249934 90)
			(size 0.06985 0.06985)
			(layers "F.Cu" "F.Mask" "F.Paste")
			(net "VR_COMP_PVPP_KLM_3")
			(options
				(clearance outline)
				(anchor circle)
			)
			(primitives
				(gr_poly
					(pts
						(arc
							(start 0.2413 -0.1397)
							(mid 0.381 0)
							(end 0.2413 0.1397)
						)
						(xy -0.381 0.1397) (xy -0.381 -0.1397)
					)
					(width 0)
					(fill yes)
				)
			)
		)
		(pad "4" smd custom
			(at -2.8321 -0.750062 90)
			(size 0.06985 0.06985)
			(layers "F.Cu" "F.Mask" "F.Paste")
			(net "VR_PVPP_KLM_ISET")
			(options
				(clearance outline)
				(anchor circle)
			)
			(primitives
				(gr_poly
					(pts
						(arc
							(start 0.2413 -0.1397)
							(mid 0.381 0)
							(end 0.2413 0.1397)
						)
						(xy -0.381 0.1397) (xy -0.381 -0.1397)
					)
					(width 0)
					(fill yes)
				)
			)
		)
		(pad "5" smd custom
			(at -2.8321 -0.249936 90)
			(size 0.06985 0.06985)
			(layers "F.Cu" "F.Mask" "F.Paste")
			(net "AGND_PVPP_KLM")
			(options
				(clearance outline)
				(anchor circle)
			)
			(primitives
				(gr_poly
					(pts
						(arc
							(start 0.2413 -0.1397)
							(mid 0.381 0)
							(end 0.2413 0.1397)
						)
						(xy -0.381 0.1397) (xy -0.381 -0.1397)
					)
					(width 0)
					(fill yes)
				)
			)
		)
		(pad "6" smd custom
			(at -2.8321 0.249936 90)
			(size 0.06985 0.06985)
			(layers "F.Cu" "F.Mask" "F.Paste")
			(net "AGND_PVPP_KLM")
			(options
				(clearance outline)
				(anchor circle)
			)
			(primitives
				(gr_poly
					(pts
						(arc
							(start 0.2413 -0.1397)
							(mid 0.381 0)
							(end 0.2413 0.1397)
						)
						(xy -0.381 0.1397) (xy -0.381 -0.1397)
					)
					(width 0)
					(fill yes)
				)
			)
		)
		(pad "7" smd custom
			(at -2.8321 0.750062 90)
			(size 0.06985 0.06985)
			(layers "F.Cu" "F.Mask" "F.Paste")
			(net "PWRGD_PVPP_KLM_R")
			(options
				(clearance outline)
				(anchor circle)
			)
			(primitives
				(gr_poly
					(pts
						(arc
							(start 0.2413 -0.1397)
							(mid 0.381 0)
							(end 0.2413 0.1397)
						)
						(xy -0.381 0.1397) (xy -0.381 -0.1397)
					)
					(width 0)
					(fill yes)
				)
			)
		)
		(pad "8" smd custom
			(at -2.8321 1.249934 90)
			(size 0.06985 0.06985)
			(layers "F.Cu" "F.Mask" "F.Paste")
			(net "VR_FET_SW_P12V_STBY_PVPP_KLM")
			(options
				(clearance outline)
				(anchor circle)
			)
			(primitives
				(gr_poly
					(pts
						(arc
							(start 0.2413 -0.1397)
							(mid 0.381 0)
							(end 0.2413 0.1397)
						)
						(xy -0.381 0.1397) (xy -0.381 -0.1397)
					)
					(width 0)
					(fill yes)
				)
			)
		)
		(pad "9" smd custom
			(at -2.8321 1.75006 90)
			(size 0.06985 0.06985)
			(layers "F.Cu" "F.Mask" "F.Paste")
			(net "VR_FET_SW_P12V_STBY_PVPP_KLM")
			(options
				(clearance outline)
				(anchor circle)
			)
			(primitives
				(gr_poly
					(pts
						(arc
							(start 0.2413 -0.1397)
							(mid 0.381 0)
							(end 0.2413 0.1397)
						)
						(xy -0.381 0.1397) (xy -0.381 -0.1397)
					)
					(width 0)
					(fill yes)
				)
			)
		)
		(pad "10" smd custom
			(at -2.8321 2.249932 90)
			(size 0.06985 0.06985)
			(layers "F.Cu" "F.Mask" "F.Paste")
			(net "VR_FET_SW_P12V_STBY_PVPP_KLM")
			(options
				(clearance outline)
				(anchor circle)
			)
			(primitives
				(gr_poly
					(pts
						(arc
							(start 0.2413 -0.1397)
							(mid 0.381 0)
							(end 0.2413 0.1397)
						)
						(xy -0.381 0.1397) (xy -0.381 -0.1397)
					)
					(width 0)
					(fill yes)
				)
			)
		)
		(pad "11" smd custom
			(at -2.249932 2.8321 90)
			(size 0.06985 0.06985)
			(layers "F.Cu" "F.Mask" "F.Paste")
			(net "VR_FET_SW_P12V_STBY_PVPP_KLM")
			(options
				(clearance outline)
				(anchor circle)
			)
			(primitives
				(gr_poly
					(pts
						(arc
							(start -0.1397 -0.2413)
							(mid 0 -0.381)
							(end 0.1397 -0.2413)
						)
						(xy 0.1397 0.381) (xy -0.1397 0.381)
					)
					(width 0)
					(fill yes)
				)
			)
		)
		(pad "12" smd custom
			(at -1.75006 2.8321 90)
			(size 0.06985 0.06985)
			(layers "F.Cu" "F.Mask" "F.Paste")
			(net "VR_FET_SW_P12V_STBY_PVPP_KLM")
			(options
				(clearance outline)
				(anchor circle)
			)
			(primitives
				(gr_poly
					(pts
						(arc
							(start -0.1397 -0.2413)
							(mid 0 -0.381)
							(end 0.1397 -0.2413)
						)
						(xy 0.1397 0.381) (xy -0.1397 0.381)
					)
					(width 0)
					(fill yes)
				)
			)
		)
		(pad "13" smd custom
			(at -1.249934 2.8321 90)
			(size 0.06985 0.06985)
			(layers "F.Cu" "F.Mask" "F.Paste")
			(net "VR_FET_SW_P12V_STBY_PVPP_KLM")
			(options
				(clearance outline)
				(anchor circle)
			)
			(primitives
				(gr_poly
					(pts
						(arc
							(start -0.1397 -0.2413)
							(mid 0 -0.381)
							(end 0.1397 -0.2413)
						)
						(xy 0.1397 0.381) (xy -0.1397 0.381)
					)
					(width 0)
					(fill yes)
				)
			)
		)
		(pad "14" smd custom
			(at -0.750062 2.8321 90)
			(size 0.06985 0.06985)
			(layers "F.Cu" "F.Mask" "F.Paste")
			(net "VR_FET_SW_P12V_STBY_PVPP_KLM")
			(options
				(clearance outline)
				(anchor circle)
			)
			(primitives
				(gr_poly
					(pts
						(arc
							(start -0.1397 -0.2413)
							(mid 0 -0.381)
							(end 0.1397 -0.2413)
						)
						(xy 0.1397 0.381) (xy -0.1397 0.381)
					)
					(width 0)
					(fill yes)
				)
			)
		)
		(pad "15" smd custom
			(at -0.249936 2.8321 90)
			(size 0.06985 0.06985)
			(layers "F.Cu" "F.Mask" "F.Paste")
			(net "VR_PVPP_KLM_PHASE")
			(options
				(clearance outline)
				(anchor circle)
			)
			(primitives
				(gr_poly
					(pts
						(arc
							(start -0.1397 -0.2413)
							(mid 0 -0.381)
							(end 0.1397 -0.2413)
						)
						(xy 0.1397 0.381) (xy -0.1397 0.381)
					)
					(width 0)
					(fill yes)
				)
			)
		)
		(pad "16" smd custom
			(at 0.249936 2.8321 90)
			(size 0.06985 0.06985)
			(layers "F.Cu" "F.Mask" "F.Paste")
			(net "GND")
			(options
				(clearance outline)
				(anchor circle)
			)
			(primitives
				(gr_poly
					(pts
						(arc
							(start -0.1397 -0.2413)
							(mid 0 -0.381)
							(end 0.1397 -0.2413)
						)
						(xy 0.1397 0.381) (xy -0.1397 0.381)
					)
					(width 0)
					(fill yes)
				)
			)
		)
		(pad "17" smd custom
			(at 0.750062 2.8321 90)
			(size 0.06985 0.06985)
			(layers "F.Cu" "F.Mask" "F.Paste")
			(net "GND")
			(options
				(clearance outline)
				(anchor circle)
			)
			(primitives
				(gr_poly
					(pts
						(arc
							(start -0.1397 -0.2413)
							(mid 0 -0.381)
							(end 0.1397 -0.2413)
						)
						(xy 0.1397 0.381) (xy -0.1397 0.381)
					)
					(width 0)
					(fill yes)
				)
			)
		)
	)
)
